(kicad_pcb
	(version 20260206)
	(generator "pcbnew")
	(generator_version "10.0")
	(general
		(thickness 1.6)
		(legacy_teardrops no)
	)
	(paper "A4")
	(title_block
		(title "04192023_DAF0TMB3IC0_F0TG_MB_C_brd_V02_OCP.brd")
		(comment 1 "Grand Teton / footprints 140-147 of 8354")
	)
	(layers
		(0 "F.Cu" signal "TOP")
		(4 "In1.Cu" signal "GND")
		(6 "In2.Cu" signal "IN1")
		(8 "In3.Cu" signal "GND1")
		(10 "In4.Cu" signal "IN2")
		(12 "In5.Cu" signal "GND2")
		(14 "In6.Cu" signal "IN3")
		(16 "In7.Cu" signal "GND3")
		(18 "In8.Cu" signal "VCC")
		(20 "In9.Cu" signal "VCC1")
		(22 "In10.Cu" signal "GND4")
		(24 "In11.Cu" signal "IN4")
		(26 "In12.Cu" signal "GND5")
		(28 "In13.Cu" signal "IN5")
		(30 "In14.Cu" signal "GND6")
		(32 "In15.Cu" signal "IN6")
		(34 "In16.Cu" signal "GND7")
		(2 "B.Cu" signal "BOTTOM")
		(9 "F.Adhes" user "F.Adhesive")
		(11 "B.Adhes" user "B.Adhesive")
		(13 "F.Paste" user "Package Geometry/Pastemask Top")
		(15 "B.Paste" user "Package Geometry/Pastemask Bottom")
		(5 "F.SilkS" user "Ref Des/Silkscreen Top")
		(7 "B.SilkS" user "Ref Des/Silkscreen Bottom")
		(1 "F.Mask" user "Board Geometry/Soldermask Top")
		(3 "B.Mask" user "Board Geometry/Soldermask Bottom")
		(17 "Dwgs.User" user "User.Drawings")
		(19 "Cmts.User" user "User.Comments")
		(21 "Eco1.User" user "User.Eco1")
		(23 "Eco2.User" user "User.Eco2")
		(25 "Edge.Cuts" user "Board Geometry/Outline")
		(27 "Margin" user)
		(31 "F.CrtYd" user "Package Geometry/Place Bound Top")
		(29 "B.CrtYd" user "Package Geometry/Place Bound Bottom")
		(35 "F.Fab" user "Ref Des/Assembly Top")
		(33 "B.Fab" user "Ref Des/Assembly Bottom")
	)
	(footprint ""
		(layer "F.Cu")
		(at 83.40725 -141.308836 90)
		(property "Reference" "U40"
			(at 1.051814 -2.801112 90)
			(unlocked yes)
			(layer "F.SilkS")
			(effects
				(font
					(size 0.7874 0.5842)
					(thickness 0.1524)
				)
			)
		)
		(property "Value" ""
			(at 0 0 90)
			(layer "F.Fab")
			(effects
				(font
					(size 1.27 1.27)
				)
			)
		)
		(duplicate_pad_numbers_are_jumpers no)
		(fp_line
			(start 1.7272 -1.1176)
			(end 0.254 -1.1176)
			(stroke
				(width 0.1524)
				(type default)
			)
			(layer "F.SilkS")
		)
		(fp_line
			(start 1.7272 -1.1176)
			(end 1.7272 1.1176)
			(stroke
				(width 0.1524)
				(type default)
			)
			(layer "F.SilkS")
		)
		(fp_line
			(start 0.254 -1.1176)
			(end 0 -0.7366)
			(stroke
				(width 0.1524)
				(type default)
			)
			(layer "F.SilkS")
		)
		(fp_line
			(start -0.254 -1.1176)
			(end -1.7272 -1.1176)
			(stroke
				(width 0.1524)
				(type default)
			)
			(layer "F.SilkS")
		)
		(fp_line
			(start 0 -0.7366)
			(end -0.254 -1.1176)
			(stroke
				(width 0.1524)
				(type default)
			)
			(layer "F.SilkS")
		)
		(fp_line
			(start 1.7272 1.1176)
			(end -1.7272 1.1176)
			(stroke
				(width 0.1524)
				(type default)
			)
			(layer "F.SilkS")
		)
		(fp_line
			(start -1.7272 1.1176)
			(end -1.7272 -1.1176)
			(stroke
				(width 0.1524)
				(type default)
			)
			(layer "F.SilkS")
		)
		(fp_poly
			(pts
				(xy -0.618998 -2.367788) (xy -0.999998 -1.605788) (xy -1.380998 -2.367788)
			)
			(stroke
				(width 0)
				(type default)
			)
			(fill yes)
			(layer "F.SilkS")
		)
		(fp_line
			(start 1.5748 -1.1176)
			(end -1.5748 -1.1176)
			(stroke
				(width 0.1)
				(type default)
			)
			(layer "F.Fab")
		)
		(fp_line
			(start -1.5748 -1.1176)
			(end -1.5748 1.1176)
			(stroke
				(width 0.1)
				(type default)
			)
			(layer "F.Fab")
		)
		(fp_line
			(start 1.5748 1.1176)
			(end 1.5748 -1.1176)
			(stroke
				(width 0.1)
				(type default)
			)
			(layer "F.Fab")
		)
		(fp_line
			(start -1.5748 1.1176)
			(end 1.5748 1.1176)
			(stroke
				(width 0.1)
				(type default)
			)
			(layer "F.Fab")
		)
		(fp_poly
			(pts
				(xy -1.9558 -0.649986) (xy -2.7178 -0.268986) (xy -2.7178 -1.030986)
			)
			(stroke
				(width 0)
				(type default)
			)
			(fill yes)
			(layer "F.Fab")
		)
		(pad "1" smd rect
			(at -0.999998 -0.649986)
			(size 0.3556 1.1176)
			(layers "F.Cu" "F.Mask" "F.Paste")
			(net "PWRGD_CPU1_PWROK")
		)
		(pad "2" smd rect
			(at -0.999998 0)
			(size 0.3556 1.1176)
			(layers "F.Cu" "F.Mask" "F.Paste")
			(net "GND")
		)
		(pad "3" smd rect
			(at -0.999998 0.649986)
			(size 0.3556 1.1176)
			(layers "F.Cu" "F.Mask" "F.Paste")
			(net "PWRGD_CPU1_PWROK")
		)
		(pad "4" smd rect
			(at 0.999998 0.649986)
			(size 0.3556 1.1176)
			(layers "F.Cu" "F.Mask" "F.Paste")
			(net "PVDDCR_CPU1_P1_RESET_N")
		)
		(pad "5" smd rect
			(at 0.999998 0)
			(size 0.3556 1.1176)
			(layers "F.Cu" "F.Mask" "F.Paste")
			(net "P1V8_AUX")
		)
		(pad "6" smd rect
			(at 0.999998 -0.649986)
			(size 0.3556 1.1176)
			(layers "F.Cu" "F.Mask" "F.Paste")
			(net "PVDDCR_CPU0_P1_RESET_N")
		)
	)
	(footprint ""
		(layer "F.Cu")
		(at 152.541986 -408.517344 -90)
		(property "Reference" "C6717"
			(at 0 0 270)
			(layer "F.SilkS")
			(hide yes)
			(effects
				(font
					(size 1.27 1.27)
				)
			)
		)
		(property "Value" ""
			(at 0 0 270)
			(layer "F.Fab")
			(effects
				(font
					(size 1.27 1.27)
				)
			)
		)
		(duplicate_pad_numbers_are_jumpers no)
		(fp_line
			(start -0.299974 0.150114)
			(end -0.299974 -0.150114)
			(stroke
				(width 0.1)
				(type default)
			)
			(layer "F.Fab")
		)
		(fp_line
			(start 0.299974 0.150114)
			(end -0.299974 0.150114)
			(stroke
				(width 0.1)
				(type default)
			)
			(layer "F.Fab")
		)
		(fp_line
			(start -0.299974 -0.150114)
			(end 0.299974 -0.150114)
			(stroke
				(width 0.1)
				(type default)
			)
			(layer "F.Fab")
		)
		(fp_line
			(start 0.299974 -0.150114)
			(end 0.299974 0.150114)
			(stroke
				(width 0.1)
				(type default)
			)
			(layer "F.Fab")
		)
		(pad "1" smd rect
			(at -0.2667 0 270)
			(size 0.3048 0.381)
			(layers "F.Cu" "F.Mask" "F.Paste")
			(net "P5E_CPU1_P2_TX_BUF_C_DP<12>")
		)
		(pad "2" smd rect
			(at 0.2667 0 270)
			(size 0.3048 0.381)
			(layers "F.Cu" "F.Mask" "F.Paste")
			(net "P5E_CPU1_P2_TX_BUF_DP<12>")
		)
	)
	(footprint ""
		(layer "F.Cu")
		(at 17.658842 -105.537762 90)
		(property "Reference" "R4420"
			(at 0 0 90)
			(layer "F.SilkS")
			(hide yes)
			(effects
				(font
					(size 1.27 1.27)
				)
			)
		)
		(property "Value" ""
			(at 0 0 90)
			(layer "F.Fab")
			(effects
				(font
					(size 1.27 1.27)
				)
			)
		)
		(duplicate_pad_numbers_are_jumpers no)
		(fp_line
			(start 0.7874 -0.4064)
			(end 0.7874 0.4064)
			(stroke
				(width 0.1524)
				(type default)
			)
			(layer "F.SilkS")
		)
		(fp_line
			(start -0.7874 -0.4064)
			(end 0.7874 -0.4064)
			(stroke
				(width 0.1524)
				(type default)
			)
			(layer "F.SilkS")
		)
		(fp_line
			(start 0.7874 0.4064)
			(end -0.7874 0.4064)
			(stroke
				(width 0.1524)
				(type default)
			)
			(layer "F.SilkS")
		)
		(fp_line
			(start -0.7874 0.4064)
			(end -0.7874 -0.4064)
			(stroke
				(width 0.1524)
				(type default)
			)
			(layer "F.SilkS")
		)
		(fp_line
			(start -0.12065 -0.305054)
			(end -0.12065 -0.2794)
			(stroke
				(width 0.1)
				(type default)
			)
			(layer "F.Fab")
		)
		(fp_line
			(start -0.67945 -0.305054)
			(end -0.12065 -0.305054)
			(stroke
				(width 0.1)
				(type default)
			)
			(layer "F.Fab")
		)
		(fp_line
			(start 0.67945 -0.3048)
			(end 0.67945 0.3048)
			(stroke
				(width 0.1)
				(type default)
			)
			(layer "F.Fab")
		)
		(fp_line
			(start 0.12065 -0.3048)
			(end 0.67945 -0.3048)
			(stroke
				(width 0.1)
				(type default)
			)
			(layer "F.Fab")
		)
		(fp_line
			(start 0.12065 -0.2794)
			(end 0.12065 -0.3048)
			(stroke
				(width 0.1)
				(type default)
			)
			(layer "F.Fab")
		)
		(fp_line
			(start -0.12065 -0.2794)
			(end 0.12065 -0.2794)
			(stroke
				(width 0.1)
				(type default)
			)
			(layer "F.Fab")
		)
		(fp_line
			(start 0.120396 0.2794)
			(end -0.12065 0.2794)
			(stroke
				(width 0.1)
				(type default)
			)
			(layer "F.Fab")
		)
		(fp_line
			(start -0.12065 0.2794)
			(end -0.12065 0.3048)
			(stroke
				(width 0.1)
				(type default)
			)
			(layer "F.Fab")
		)
		(fp_line
			(start 0.67945 0.3048)
			(end 0.120396 0.3048)
			(stroke
				(width 0.1)
				(type default)
			)
			(layer "F.Fab")
		)
		(fp_line
			(start 0.120396 0.3048)
			(end 0.120396 0.2794)
			(stroke
				(width 0.1)
				(type default)
			)
			(layer "F.Fab")
		)
		(fp_line
			(start -0.12065 0.3048)
			(end -0.67945 0.3048)
			(stroke
				(width 0.1)
				(type default)
			)
			(layer "F.Fab")
		)
		(fp_line
			(start -0.67945 0.3048)
			(end -0.67945 -0.305054)
			(stroke
				(width 0.1)
				(type default)
			)
			(layer "F.Fab")
		)
		(pad "1" smd circle
			(at -0.40005 0 90)
			(size 0 0)
			(layers "F.Cu" "F.Mask" "F.Paste")
			(net "USB2_HOST_BMC_B_DN")
		)
		(pad "2" smd circle
			(at 0.40005 0 90)
			(size 0 0)
			(layers "F.Cu" "F.Mask" "F.Paste")
			(net "GND")
		)
	)
	(footprint ""
		(layer "F.Cu")
		(at 85.442044 -408.517344 -90)
		(property "Reference" "C6653"
			(at 0 0 270)
			(layer "F.SilkS")
			(hide yes)
			(effects
				(font
					(size 1.27 1.27)
				)
			)
		)
		(property "Value" ""
			(at 0 0 270)
			(layer "F.Fab")
			(effects
				(font
					(size 1.27 1.27)
				)
			)
		)
		(duplicate_pad_numbers_are_jumpers no)
		(fp_line
			(start -0.299974 0.150114)
			(end -0.299974 -0.150114)
			(stroke
				(width 0.1)
				(type default)
			)
			(layer "F.Fab")
		)
		(fp_line
			(start 0.299974 0.150114)
			(end -0.299974 0.150114)
			(stroke
				(width 0.1)
				(type default)
			)
			(layer "F.Fab")
		)
		(fp_line
			(start -0.299974 -0.150114)
			(end 0.299974 -0.150114)
			(stroke
				(width 0.1)
				(type default)
			)
			(layer "F.Fab")
		)
		(fp_line
			(start 0.299974 -0.150114)
			(end 0.299974 0.150114)
			(stroke
				(width 0.1)
				(type default)
			)
			(layer "F.Fab")
		)
		(pad "1" smd rect
			(at -0.2667 0 270)
			(size 0.3048 0.381)
			(layers "F.Cu" "F.Mask" "F.Paste")
			(net "P5E_CPU1_P0_TX_BUF_C_DP<12>")
		)
		(pad "2" smd rect
			(at 0.2667 0 270)
			(size 0.3048 0.381)
			(layers "F.Cu" "F.Mask" "F.Paste")
			(net "P5E_CPU1_P0_TX_BUF_DP<12>")
		)
	)
	(footprint ""
		(layer "F.Cu")
		(at 420.913306 -432.876198)
		(property "Reference" "R1085"
			(at 0 0 0)
			(layer "F.SilkS")
			(hide yes)
			(effects
				(font
					(size 1.27 1.27)
				)
			)
		)
		(property "Value" ""
			(at 0 0 0)
			(layer "F.Fab")
			(effects
				(font
					(size 1.27 1.27)
				)
			)
		)
		(duplicate_pad_numbers_are_jumpers no)
		(fp_line
			(start -0.32512 -0.175006)
			(end 0.32512 -0.175006)
			(stroke
				(width 0.1)
				(type default)
			)
			(layer "F.Fab")
		)
		(fp_line
			(start -0.32512 0.175006)
			(end -0.32512 -0.175006)
			(stroke
				(width 0.1)
				(type default)
			)
			(layer "F.Fab")
		)
		(fp_line
			(start 0.32512 -0.175006)
			(end 0.32512 0.175006)
			(stroke
				(width 0.1)
				(type default)
			)
			(layer "F.Fab")
		)
		(fp_line
			(start 0.32512 0.175006)
			(end -0.32512 0.175006)
			(stroke
				(width 0.1)
				(type default)
			)
			(layer "F.Fab")
		)
		(pad "1" smd rect
			(at -0.2667 0)
			(size 0.3048 0.381)
			(layers "F.Cu" "F.Mask" "F.Paste")
			(net "U16_E2")
		)
		(pad "2" smd rect
			(at 0.2667 0 180)
			(size 0.3048 0.381)
			(layers "F.Cu" "F.Mask" "F.Paste")
			(net "GND")
		)
	)
	(footprint ""
		(layer "F.Cu")
		(at 116.225828 -256.012442 90)
		(property "Reference" "C3900"
			(at 0 0 90)
			(layer "F.SilkS")
			(hide yes)
			(effects
				(font
					(size 1.27 1.27)
				)
			)
		)
		(property "Value" ""
			(at 0 0 90)
			(layer "F.Fab")
			(effects
				(font
					(size 1.27 1.27)
				)
			)
		)
		(duplicate_pad_numbers_are_jumpers no)
		(fp_line
			(start 0.7874 -0.4064)
			(end 0.7874 0.4064)
			(stroke
				(width 0.1524)
				(type default)
			)
			(layer "F.SilkS")
		)
		(fp_line
			(start -0.7874 -0.4064)
			(end 0.7874 -0.4064)
			(stroke
				(width 0.1524)
				(type default)
			)
			(layer "F.SilkS")
		)
		(fp_line
			(start 0.7874 0.4064)
			(end -0.7874 0.4064)
			(stroke
				(width 0.1524)
				(type default)
			)
			(layer "F.SilkS")
		)
		(fp_line
			(start -0.7874 0.4064)
			(end -0.7874 -0.4064)
			(stroke
				(width 0.1524)
				(type default)
			)
			(layer "F.SilkS")
		)
		(fp_line
			(start -0.12065 -0.305054)
			(end -0.12065 -0.2794)
			(stroke
				(width 0.1)
				(type default)
			)
			(layer "F.Fab")
		)
		(fp_line
			(start -0.67945 -0.305054)
			(end -0.12065 -0.305054)
			(stroke
				(width 0.1)
				(type default)
			)
			(layer "F.Fab")
		)
		(fp_line
			(start 0.67945 -0.3048)
			(end 0.67945 0.3048)
			(stroke
				(width 0.1)
				(type default)
			)
			(layer "F.Fab")
		)
		(fp_line
			(start 0.12065 -0.3048)
			(end 0.67945 -0.3048)
			(stroke
				(width 0.1)
				(type default)
			)
			(layer "F.Fab")
		)
		(fp_line
			(start 0.12065 -0.2794)
			(end 0.12065 -0.3048)
			(stroke
				(width 0.1)
				(type default)
			)
			(layer "F.Fab")
		)
		(fp_line
			(start -0.12065 -0.2794)
			(end 0.12065 -0.2794)
			(stroke
				(width 0.1)
				(type default)
			)
			(layer "F.Fab")
		)
		(fp_line
			(start 0.120396 0.2794)
			(end -0.12065 0.2794)
			(stroke
				(width 0.1)
				(type default)
			)
			(layer "F.Fab")
		)
		(fp_line
			(start -0.12065 0.2794)
			(end -0.12065 0.3048)
			(stroke
				(width 0.1)
				(type default)
			)
			(layer "F.Fab")
		)
		(fp_line
			(start 0.67945 0.3048)
			(end 0.120396 0.3048)
			(stroke
				(width 0.1)
				(type default)
			)
			(layer "F.Fab")
		)
		(fp_line
			(start 0.120396 0.3048)
			(end 0.120396 0.2794)
			(stroke
				(width 0.1)
				(type default)
			)
			(layer "F.Fab")
		)
		(fp_line
			(start -0.12065 0.3048)
			(end -0.67945 0.3048)
			(stroke
				(width 0.1)
				(type default)
			)
			(layer "F.Fab")
		)
		(fp_line
			(start -0.67945 0.3048)
			(end -0.67945 -0.305054)
			(stroke
				(width 0.1)
				(type default)
			)
			(layer "F.Fab")
		)
		(pad "1" smd circle
			(at -0.40005 0 90)
			(size 0 0)
			(layers "F.Cu" "F.Mask" "F.Paste")
			(net "PVDDCR_SOC_P1")
		)
		(pad "2" smd circle
			(at 0.40005 0 90)
			(size 0 0)
			(layers "F.Cu" "F.Mask" "F.Paste")
			(net "GND")
		)
	)
	(footprint ""
		(layer "F.Cu")
		(at 350.44761 -61.364876 180)
		(property "Reference" "R483"
			(at 0 0 180)
			(layer "F.SilkS")
			(hide yes)
			(effects
				(font
					(size 1.27 1.27)
				)
			)
		)
		(property "Value" ""
			(at 0 0 180)
			(layer "F.Fab")
			(effects
				(font
					(size 1.27 1.27)
				)
			)
		)
		(duplicate_pad_numbers_are_jumpers no)
		(fp_line
			(start 0.7874 0.4064)
			(end -0.7874 0.4064)
			(stroke
				(width 0.1524)
				(type default)
			)
			(layer "F.SilkS")
		)
		(fp_line
			(start 0.7874 -0.4064)
			(end 0.7874 0.4064)
			(stroke
				(width 0.1524)
				(type default)
			)
			(layer "F.SilkS")
		)
		(fp_line
			(start -0.7874 0.4064)
			(end -0.7874 -0.4064)
			(stroke
				(width 0.1524)
				(type default)
			)
			(layer "F.SilkS")
		)
		(fp_line
			(start -0.7874 -0.4064)
			(end 0.7874 -0.4064)
			(stroke
				(width 0.1524)
				(type default)
			)
			(layer "F.SilkS")
		)
		(fp_line
			(start 0.67945 0.3048)
			(end 0.120396 0.3048)
			(stroke
				(width 0.1)
				(type default)
			)
			(layer "F.Fab")
		)
		(fp_line
			(start 0.67945 -0.3048)
			(end 0.67945 0.3048)
			(stroke
				(width 0.1)
				(type default)
			)
			(layer "F.Fab")
		)
		(fp_line
			(start 0.12065 -0.2794)
			(end 0.12065 -0.3048)
			(stroke
				(width 0.1)
				(type default)
			)
			(layer "F.Fab")
		)
		(fp_line
			(start 0.12065 -0.3048)
			(end 0.67945 -0.3048)
			(stroke
				(width 0.1)
				(type default)
			)
			(layer "F.Fab")
		)
		(fp_line
			(start 0.120396 0.3048)
			(end 0.120396 0.2794)
			(stroke
				(width 0.1)
				(type default)
			)
			(layer "F.Fab")
		)
		(fp_line
			(start 0.120396 0.2794)
			(end -0.12065 0.2794)
			(stroke
				(width 0.1)
				(type default)
			)
			(layer "F.Fab")
		)
		(fp_line
			(start -0.12065 0.3048)
			(end -0.67945 0.3048)
			(stroke
				(width 0.1)
				(type default)
			)
			(layer "F.Fab")
		)
		(fp_line
			(start -0.12065 0.2794)
			(end -0.12065 0.3048)
			(stroke
				(width 0.1)
				(type default)
			)
			(layer "F.Fab")
		)
		(fp_line
			(start -0.12065 -0.2794)
			(end 0.12065 -0.2794)
			(stroke
				(width 0.1)
				(type default)
			)
			(layer "F.Fab")
		)
		(fp_line
			(start -0.12065 -0.305054)
			(end -0.12065 -0.2794)
			(stroke
				(width 0.1)
				(type default)
			)
			(layer "F.Fab")
		)
		(fp_line
			(start -0.67945 0.3048)
			(end -0.67945 -0.305054)
			(stroke
				(width 0.1)
				(type default)
			)
			(layer "F.Fab")
		)
		(fp_line
			(start -0.67945 -0.305054)
			(end -0.12065 -0.305054)
			(stroke
				(width 0.1)
				(type default)
			)
			(layer "F.Fab")
		)
		(pad "1" smd circle
			(at -0.40005 0 180)
			(size 0 0)
			(layers "F.Cu" "F.Mask" "F.Paste")
			(net "CPU0_XTRIG_L5")
		)
		(pad "2" smd circle
			(at 0.40005 0 180)
			(size 0 0)
			(layers "F.Cu" "F.Mask" "F.Paste")
			(net "CPU0_XTRIG_R1_L5")
		)
	)
	(footprint ""
		(layer "F.Cu")
		(at 209.423 -129.54 90)
		(property "Reference" "C29"
			(at 0 0 90)
			(layer "F.SilkS")
			(hide yes)
			(effects
				(font
					(size 1.27 1.27)
				)
			)
		)
		(property "Value" ""
			(at 0 0 90)
			(layer "F.Fab")
			(effects
				(font
					(size 1.27 1.27)
				)
			)
		)
		(duplicate_pad_numbers_are_jumpers no)
		(fp_line
			(start 0.7874 -0.4064)
			(end 0.7874 0.4064)
			(stroke
				(width 0.1524)
				(type default)
			)
			(layer "F.SilkS")
		)
		(fp_line
			(start -0.7874 -0.4064)
			(end 0.7874 -0.4064)
			(stroke
				(width 0.1524)
				(type default)
			)
			(layer "F.SilkS")
		)
		(fp_line
			(start 0.7874 0.4064)
			(end -0.7874 0.4064)
			(stroke
				(width 0.1524)
				(type default)
			)
			(layer "F.SilkS")
		)
		(fp_line
			(start -0.7874 0.4064)
			(end -0.7874 -0.4064)
			(stroke
				(width 0.1524)
				(type default)
			)
			(layer "F.SilkS")
		)
		(fp_line
			(start -0.12065 -0.305054)
			(end -0.12065 -0.2794)
			(stroke
				(width 0.1)
				(type default)
			)
			(layer "F.Fab")
		)
		(fp_line
			(start -0.67945 -0.305054)
			(end -0.12065 -0.305054)
			(stroke
				(width 0.1)
				(type default)
			)
			(layer "F.Fab")
		)
		(fp_line
			(start 0.67945 -0.3048)
			(end 0.67945 0.3048)
			(stroke
				(width 0.1)
				(type default)
			)
			(layer "F.Fab")
		)
		(fp_line
			(start 0.12065 -0.3048)
			(end 0.67945 -0.3048)
			(stroke
				(width 0.1)
				(type default)
			)
			(layer "F.Fab")
		)
		(fp_line
			(start 0.12065 -0.2794)
			(end 0.12065 -0.3048)
			(stroke
				(width 0.1)
				(type default)
			)
			(layer "F.Fab")
		)
		(fp_line
			(start -0.12065 -0.2794)
			(end 0.12065 -0.2794)
			(stroke
				(width 0.1)
				(type default)
			)
			(layer "F.Fab")
		)
		(fp_line
			(start 0.120396 0.2794)
			(end -0.12065 0.2794)
			(stroke
				(width 0.1)
				(type default)
			)
			(layer "F.Fab")
		)
		(fp_line
			(start -0.12065 0.2794)
			(end -0.12065 0.3048)
			(stroke
				(width 0.1)
				(type default)
			)
			(layer "F.Fab")
		)
		(fp_line
			(start 0.67945 0.3048)
			(end 0.120396 0.3048)
			(stroke
				(width 0.1)
				(type default)
			)
			(layer "F.Fab")
		)
		(fp_line
			(start 0.120396 0.3048)
			(end 0.120396 0.2794)
			(stroke
				(width 0.1)
				(type default)
			)
			(layer "F.Fab")
		)
		(fp_line
			(start -0.12065 0.3048)
			(end -0.67945 0.3048)
			(stroke
				(width 0.1)
				(type default)
			)
			(layer "F.Fab")
		)
		(fp_line
			(start -0.67945 0.3048)
			(end -0.67945 -0.305054)
			(stroke
				(width 0.1)
				(type default)
			)
			(layer "F.Fab")
		)
		(pad "1" smd circle
			(at -0.40005 0 90)
			(size 0 0)
			(layers "F.Cu" "F.Mask" "F.Paste")
			(net "SW_P3V3_EN_ISO_R")
		)
		(pad "2" smd circle
			(at 0.40005 0 90)
			(size 0 0)
			(layers "F.Cu" "F.Mask" "F.Paste")
			(net "GND")
		)
	)
)
